(kicad_pcb
	(version 20211014)
	(generator pcbnew)
	(general
    (thickness 1.6)
  )
	(paper "A4")
	(title_block
    (title "SA800U (Snapdragon 845) Baseboard")
    (date "2023-10-19")
    (rev "1.0.3")
    (company "Antmicro Ltd.")
    (comment 1 "www.antmicro.com")
		(comment 9 "footprints 290-297 of 589")
	)
	(layers
    (0 "F.Cu" signal)
    (1 "In1.Cu" power)
    (2 "In2.Cu" signal)
    (3 "In3.Cu" signal)
    (4 "In4.Cu" power)
    (31 "B.Cu" signal)
    (32 "B.Adhes" user "B.Adhesive")
    (33 "F.Adhes" user "F.Adhesive")
    (34 "B.Paste" user)
    (35 "F.Paste" user)
    (36 "B.SilkS" user "B.Silkscreen")
    (37 "F.SilkS" user "F.Silkscreen")
    (38 "B.Mask" user)
    (39 "F.Mask" user)
    (40 "Dwgs.User" user "User.Drawings")
    (41 "Cmts.User" user "User.Comments")
    (42 "Eco1.User" user "User.Eco1")
    (43 "Eco2.User" user "User.Eco2")
    (44 "Edge.Cuts" user)
    (45 "Margin" user)
    (46 "B.CrtYd" user "B.Courtyard")
    (47 "F.CrtYd" user "F.Courtyard")
    (48 "B.Fab" user)
    (49 "F.Fab" user)
  )
	(footprint "sa800u-baseboard-hw-footprints:L_Murata_025020_0605Metric" (layer "B.Cu")
    (tedit 61AA2C4F)
    (at 105.7 93.7 90)
    (property "Author" "Antmicro")
    (property "License" "Apache-2.0")
    (property "MPN" "NFP0QHB242HS2D")
    (property "Manufacturer" "Murata")
    (property "Sheetfile" "camera-interface.kicad_sch")
    (property "Sheetname" "Camera Interface")
    (attr smd)
    (fp_text reference "L24" (at -0.45 0.43 270) (layer "B.SilkS")
      (effects (font (size 0.7 0.7) (thickness 0.15)) (justify left bottom mirror))
    )
    (fp_text value "NFP0QHB242HS2D" (at 0 -1.55 270) (layer "B.Fab")
      (effects (font (size 0.7 0.7) (thickness 0.15)) (justify left bottom mirror))
    )
    (fp_text user "License: Apache-2.0" (at -1.027 -5.805 270) (layer "B.Fab") hide
      (effects (font (size 0.7 0.7) (thickness 0.15)) (justify left bottom mirror))
    )
    (fp_text user "${REFERENCE}" (at -1.027 -3.406 270) (layer "B.Fab") hide
      (effects (font (size 0.7 0.7) (thickness 0.15)) (justify left bottom mirror))
    )
    (fp_text user "Author: Antmicro" (at -1.027 -4.605 270) (layer "B.Fab") hide
      (effects (font (size 0.7 0.7) (thickness 0.15)) (justify left bottom mirror))
    )
    (fp_line (start 0.276 0.45) (end -0.276 0.45) (layer "B.SilkS") (width 0.15))
    (fp_line (start -0.276 -0.45) (end 0.276 -0.45) (layer "B.SilkS") (width 0.15))
    (fp_circle (center -0.5 0.5) (end -0.449 0.5) (layer "B.SilkS") (width 0.15) (fill solid))
    (fp_rect (start -0.5 0.6) (end 0.5 -0.6) (layer "B.CrtYd") (width 0.05) (fill none))
    (fp_line (start -0.277 -0.349) (end 0.275 -0.349) (layer "B.Fab") (width 0.15))
    (fp_line (start 0.275 -0.349) (end 0.275 0.351) (layer "B.Fab") (width 0.15))
    (fp_line (start 0.275 0.351) (end -0.277 0.351) (layer "B.Fab") (width 0.15))
    (fp_line (start -0.277 0.351) (end -0.277 -0.349) (layer "B.Fab") (width 0.15))
    (pad "1" smd rect (at -0.25 0.24 90) (size 0.3 0.23) (layers "B.Cu" "B.Paste" "B.Mask")
      (net 34 "CSI0_LN0_P") (pinfunction "1") (pintype "passive"))
    (pad "2" smd rect (at 0.248 0.24 90) (size 0.3 0.23) (layers "B.Cu" "B.Paste" "B.Mask")
      (net 266 "/Camera Interface/CSI0_LN0_FFC_P") (pinfunction "2") (pintype "passive"))
    (pad "3" smd rect (at 0.248 -0.239 90) (size 0.3 0.23) (layers "B.Cu" "B.Paste" "B.Mask")
      (net 267 "/Camera Interface/CSI0_LN0_FFC_N") (pinfunction "3") (pintype "passive"))
    (pad "4" smd rect (at -0.25 -0.239 90) (size 0.3 0.23) (layers "B.Cu" "B.Paste" "B.Mask")
      (net 33 "CSI0_LN0_N") (pinfunction "4") (pintype "passive"))
  )
	(footprint "sa800u-baseboard-hw-footprints:L_Murata_025020_0605Metric" (layer "B.Cu")
    (tedit 61AA2C4F)
    (at 107 93.7 90)
    (property "Author" "Antmicro")
    (property "License" "Apache-2.0")
    (property "MPN" "NFP0QHB242HS2D")
    (property "Manufacturer" "Murata")
    (property "Sheetfile" "camera-interface.kicad_sch")
    (property "Sheetname" "Camera Interface")
    (attr smd)
    (fp_text reference "L25" (at -0.45 0.43 270) (layer "B.SilkS")
      (effects (font (size 0.7 0.7) (thickness 0.15)) (justify left bottom mirror))
    )
    (fp_text value "NFP0QHB242HS2D" (at 0 -1.55 270) (layer "B.Fab")
      (effects (font (size 0.7 0.7) (thickness 0.15)) (justify left bottom mirror))
    )
    (fp_text user "${REFERENCE}" (at -1.027 -3.406 270) (layer "B.Fab") hide
      (effects (font (size 0.7 0.7) (thickness 0.15)) (justify left bottom mirror))
    )
    (fp_text user "Author: Antmicro" (at -1.027 -4.605 270) (layer "B.Fab") hide
      (effects (font (size 0.7 0.7) (thickness 0.15)) (justify left bottom mirror))
    )
    (fp_text user "License: Apache-2.0" (at -1.027 -5.805 270) (layer "B.Fab") hide
      (effects (font (size 0.7 0.7) (thickness 0.15)) (justify left bottom mirror))
    )
    (fp_line (start -0.276 -0.45) (end 0.276 -0.45) (layer "B.SilkS") (width 0.15))
    (fp_line (start 0.276 0.45) (end -0.276 0.45) (layer "B.SilkS") (width 0.15))
    (fp_circle (center -0.5 0.5) (end -0.449 0.5) (layer "B.SilkS") (width 0.15) (fill solid))
    (fp_rect (start -0.5 0.6) (end 0.5 -0.6) (layer "B.CrtYd") (width 0.05) (fill none))
    (fp_line (start -0.277 0.351) (end -0.277 -0.349) (layer "B.Fab") (width 0.15))
    (fp_line (start 0.275 -0.349) (end 0.275 0.351) (layer "B.Fab") (width 0.15))
    (fp_line (start -0.277 -0.349) (end 0.275 -0.349) (layer "B.Fab") (width 0.15))
    (fp_line (start 0.275 0.351) (end -0.277 0.351) (layer "B.Fab") (width 0.15))
    (pad "1" smd rect (at -0.25 0.24 90) (size 0.3 0.23) (layers "B.Cu" "B.Paste" "B.Mask")
      (net 13 "CSI0_CLK_P") (pinfunction "1") (pintype "passive"))
    (pad "2" smd rect (at 0.248 0.24 90) (size 0.3 0.23) (layers "B.Cu" "B.Paste" "B.Mask")
      (net 324 "/Camera Interface/CSI0_CLK_FFC_P") (pinfunction "2") (pintype "passive"))
    (pad "3" smd rect (at 0.248 -0.239 90) (size 0.3 0.23) (layers "B.Cu" "B.Paste" "B.Mask")
      (net 325 "/Camera Interface/CSI0_CLK_FFC_N") (pinfunction "3") (pintype "passive"))
    (pad "4" smd rect (at -0.25 -0.239 90) (size 0.3 0.23) (layers "B.Cu" "B.Paste" "B.Mask")
      (net 12 "CSI0_CLK_N") (pinfunction "4") (pintype "passive"))
  )
	(footprint "sa800u-baseboard-hw-footprints:C_0402_1005Metric" (layer "B.Cu")
    (tedit 616D63CF)
    (at 63.5 138.9 -90)
    (descr "Capacitor SMD 0402")
    (tags "capacitor SMD 0402")
    (property "Author" "Antmicro")
    (property "Dielectric" "X7R")
    (property "License" "Apache-2.0")
    (property "MPN" "GRM155R71H103KA88D")
    (property "Manufacturer" "Murata")
    (property "Sheetfile" "ethernet-controller.kicad_sch")
    (property "Sheetname" "Ethernet Controller")
    (property "Val" "10n")
    (property "Voltage" "50V")
    (attr smd)
    (fp_text reference "C16" (at -1.12 0.62 90) (layer "B.SilkS")
      (effects (font (size 0.7 0.7) (thickness 0.15)) (justify left bottom mirror))
    )
    (fp_text value "C_10n_0402" (at 0 -1.4 90) (layer "B.Fab")
      (effects (font (size 0.7 0.7) (thickness 0.15)) (justify left bottom mirror))
    )
    (fp_text user "${REFERENCE}" (at -0.932 -3.168 90) (layer "B.Fab") hide
      (effects (font (size 0.7 0.7) (thickness 0.15)) (justify left bottom mirror))
    )
    (fp_text user "License: Apache-2.0" (at -0.932 -5.17 90) (layer "B.Fab") hide
      (effects (font (size 0.7 0.7) (thickness 0.15)) (justify left bottom mirror))
    )
    (fp_text user "Author: Antmicro" (at -0.932 -4.17 90) (layer "B.Fab") hide
      (effects (font (size 0.7 0.7) (thickness 0.15)) (justify left bottom mirror))
    )
    (fp_rect (start -0.94 0.47) (end 0.94 -0.47) (layer "B.CrtYd") (width 0.05) (fill none))
    (fp_rect (start -0.499 0.249) (end 0.499 -0.249) (layer "B.Fab") (width 0.15) (fill none))
    (pad "1" smd roundrect (at -0.484 0 270) (size 0.59 0.64) (layers "B.Cu" "B.Paste" "B.Mask") (roundrect_rratio 0.25)
      (net 63 "Net-(C16-Pad1)") (pintype "passive"))
    (pad "2" smd roundrect (at 0.484 0 270) (size 0.59 0.64) (layers "B.Cu" "B.Paste" "B.Mask") (roundrect_rratio 0.25)
      (net 4 "Earth") (pintype "passive"))
  )
	(footprint "sa800u-baseboard-hw-footprints:C_0603_1608Metric" (layer "B.Cu")
    (tedit 5D5E94D2)
    (at 82.9 98.3 90)
    (descr "Capacitor SMD 0603")
    (tags "capacitor 0603")
    (property "Author" "Antmicro")
    (property "Dielectric" "")
    (property "License" "Apache-2.0")
    (property "MPN" "GRM188R60J226MEA0D")
    (property "Manufacturer" "Murata")
    (property "Sheetfile" "psu.kicad_sch")
    (property "Sheetname" "PSU")
    (property "Val" "22u")
    (property "Voltage" "")
    (attr smd)
    (fp_text reference "C128" (at 1.46 -0.86 270) (layer "B.SilkS")
      (effects (font (size 0.7 0.7) (thickness 0.15)) (justify left bottom mirror))
    )
    (fp_text value "C_22u_0603" (at 0 -1.6 270) (layer "B.Fab")
      (effects (font (size 0.7 0.7) (thickness 0.15)) (justify left bottom mirror))
    )
    (fp_text user "${REFERENCE}" (at -1.682 -3.895 270) (layer "B.Fab") hide
      (effects (font (size 0.7 0.7) (thickness 0.15)) (justify left bottom mirror))
    )
    (fp_text user "License: Apache-2.0" (at -1.682 -5.895 270) (layer "B.Fab") hide
      (effects (font (size 0.7 0.7) (thickness 0.15)) (justify left bottom mirror))
    )
    (fp_text user "Author: Antmicro" (at -1.682 -4.894 270) (layer "B.Fab") hide
      (effects (font (size 0.7 0.7) (thickness 0.15)) (justify left bottom mirror))
    )
    (fp_line (start -0.3 -0.3) (end 0.3 -0.3) (layer "B.SilkS") (width 0.15))
    (fp_line (start -0.3 0.3) (end 0.3 0.3) (layer "B.SilkS") (width 0.15))
    (fp_rect (start -1.24 0.7) (end 1.24 -0.7) (layer "B.CrtYd") (width 0.05) (fill none))
    (fp_rect (start -0.8 0.4) (end 0.8 -0.4) (layer "B.Fab") (width 0.15) (fill none))
    (pad "1" smd roundrect (at -0.7 0 90) (size 0.6 0.8) (layers "B.Cu" "B.Paste" "B.Mask") (roundrect_rratio 0.2)
      (net 74 "VDD") (pintype "passive"))
    (pad "2" smd roundrect (at 0.7 0 90) (size 0.6 0.8) (layers "B.Cu" "B.Paste" "B.Mask") (roundrect_rratio 0.2)
      (net 1 "GND") (pintype "passive"))
  )
	(footprint "sa800u-baseboard-hw-footprints:SOT-23-5" (layer "B.Cu")
    (tedit 5D64D240)
    (at 78.7 121.55)
    (property "Author" "Antmicro")
    (property "License" "Apache-2.0")
    (property "MPN" "LMV431IM5")
    (property "Manufacturer" "Texas Instruments")
    (property "Sheetfile" "psu.kicad_sch")
    (property "Sheetname" "PSU")
    (attr smd)
    (fp_text reference "U18" (at -3.04 2.38) (layer "B.SilkS")
      (effects (font (size 0.7 0.7) (thickness 0.15)) (justify right bottom mirror))
    )
    (fp_text value "LMV431_SOT-23-5" (at 0.002 -2.799) (layer "B.Fab")
      (effects (font (size 0.7 0.7) (thickness 0.15)) (justify right bottom mirror))
    )
    (fp_text user "Author: Antmicro" (at -1.898 -5.499) (layer "B.Fab") hide
      (effects (font (size 0.7 0.7) (thickness 0.15)) (justify right bottom mirror))
    )
    (fp_text user "License: Apache-2.0" (at -1.898 -6.7) (layer "B.Fab") hide
      (effects (font (size 0.7 0.7) (thickness 0.15)) (justify right bottom mirror))
    )
    (fp_text user "${REFERENCE}" (at -1.898 -4.299) (layer "B.Fab") hide
      (effects (font (size 0.7 0.7) (thickness 0.15)) (justify right bottom mirror))
    )
    (fp_line (start -0.8 1.6) (end -0.8 1.3) (layer "B.SilkS") (width 0.15))
    (fp_line (start -0.8 1.6) (end -0.5 1.6) (layer "B.SilkS") (width 0.15))
    (fp_line (start 0.8 -1.3) (end 0.8 -1.599) (layer "B.SilkS") (width 0.15))
    (fp_line (start 0.8 -0.55) (end 0.8 0.55) (layer "B.SilkS") (width 0.15))
    (fp_line (start 0.8 1.6) (end 0.5 1.6) (layer "B.SilkS") (width 0.15))
    (fp_line (start -0.85 -1.6) (end -0.85 -1.301) (layer "B.SilkS") (width 0.15))
    (fp_line (start -0.55 -1.6) (end -0.85 -1.6) (layer "B.SilkS") (width 0.15))
    (fp_line (start 0.8 1.3) (end 0.8 1.6) (layer "B.SilkS") (width 0.15))
    (fp_line (start 0.8 -1.599) (end 0.549 -1.599) (layer "B.SilkS") (width 0.15))
    (fp_circle (center -1.25 1.5) (end -1.2 1.5) (layer "B.SilkS") (width 0.15) (fill solid))
    (fp_rect (start 1.9 1.76) (end -1.9 -1.75) (layer "B.CrtYd") (width 0.05) (fill none))
    (fp_line (start -0.398 1.526) (end -0.874 1.05) (layer "B.Fab") (width 0.15))
    (fp_rect (start 0.874 -1.523) (end -0.873 1.525) (layer "B.Fab") (width 0.15) (fill none))
    (pad "1" smd rect (at -1.351 0.951 90) (size 0.55 1) (layers "B.Cu" "B.Paste" "B.Mask")
      (net 666 "unconnected-(U18-Pad1)") (pinfunction "NC") (pintype "no_connect"))
    (pad "2" smd rect (at -1.351 0 90) (size 0.55 1) (layers "B.Cu" "B.Paste" "B.Mask")
      (net 667 "unconnected-(U18-Pad2)") (pinfunction "NC") (pintype "no_connect"))
    (pad "3" smd rect (at -1.351 -0.949 90) (size 0.55 1) (layers "B.Cu" "B.Paste" "B.Mask")
      (net 406 "Net-(R125-Pad2)") (pintype "passive"))
    (pad "4" smd rect (at 1.35 -0.949 90) (size 0.55 1) (layers "B.Cu" "B.Paste" "B.Mask")
      (net 405 "Net-(R123-Pad2)") (pintype "passive"))
    (pad "5" smd rect (at 1.35 0.951 90) (size 0.55 1) (layers "B.Cu" "B.Paste" "B.Mask")
      (net 1 "GND") (pintype "passive"))
  )
	(footprint "sa800u-baseboard-hw-footprints:L_Murata_025020_0605Metric" (layer "B.Cu")
    (tedit 61AA2C4F)
    (at 92.4 93.7 90)
    (property "Author" "Antmicro")
    (property "License" "Apache-2.0")
    (property "MPN" "NFP0QHB242HS2D")
    (property "Manufacturer" "Murata")
    (property "Sheetfile" "camera-interface.kicad_sch")
    (property "Sheetname" "Camera Interface")
    (attr smd)
    (fp_text reference "L16" (at -0.44 0.33 270) (layer "B.SilkS")
      (effects (font (size 0.7 0.7) (thickness 0.15)) (justify left bottom mirror))
    )
    (fp_text value "NFP0QHB242HS2D" (at 0 -1.55 270) (layer "B.Fab")
      (effects (font (size 0.7 0.7) (thickness 0.15)) (justify left bottom mirror))
    )
    (fp_text user "${REFERENCE}" (at -1.027 -3.406 270) (layer "B.Fab") hide
      (effects (font (size 0.7 0.7) (thickness 0.15)) (justify left bottom mirror))
    )
    (fp_text user "Author: Antmicro" (at -1.027 -4.605 270) (layer "B.Fab") hide
      (effects (font (size 0.7 0.7) (thickness 0.15)) (justify left bottom mirror))
    )
    (fp_text user "License: Apache-2.0" (at -1.027 -5.805 270) (layer "B.Fab") hide
      (effects (font (size 0.7 0.7) (thickness 0.15)) (justify left bottom mirror))
    )
    (fp_line (start -0.276 -0.45) (end 0.276 -0.45) (layer "B.SilkS") (width 0.15))
    (fp_line (start 0.276 0.45) (end -0.276 0.45) (layer "B.SilkS") (width 0.15))
    (fp_circle (center -0.5 0.5) (end -0.449 0.5) (layer "B.SilkS") (width 0.15) (fill solid))
    (fp_rect (start -0.5 0.6) (end 0.5 -0.6) (layer "B.CrtYd") (width 0.05) (fill none))
    (fp_line (start 0.275 0.351) (end -0.277 0.351) (layer "B.Fab") (width 0.15))
    (fp_line (start 0.275 -0.349) (end 0.275 0.351) (layer "B.Fab") (width 0.15))
    (fp_line (start -0.277 -0.349) (end 0.275 -0.349) (layer "B.Fab") (width 0.15))
    (fp_line (start -0.277 0.351) (end -0.277 -0.349) (layer "B.Fab") (width 0.15))
    (pad "1" smd rect (at -0.25 0.24 90) (size 0.3 0.23) (layers "B.Cu" "B.Paste" "B.Mask")
      (net 17 "CSI1_LN3_P") (pinfunction "1") (pintype "passive"))
    (pad "2" smd rect (at 0.248 0.24 90) (size 0.3 0.23) (layers "B.Cu" "B.Paste" "B.Mask")
      (net 282 "/Camera Interface/CSI1_LN3_FFC_P") (pinfunction "2") (pintype "passive"))
    (pad "3" smd rect (at 0.248 -0.239 90) (size 0.3 0.23) (layers "B.Cu" "B.Paste" "B.Mask")
      (net 283 "/Camera Interface/CSI1_LN3_FFC_N") (pinfunction "3") (pintype "passive"))
    (pad "4" smd rect (at -0.25 -0.239 90) (size 0.3 0.23) (layers "B.Cu" "B.Paste" "B.Mask")
      (net 18 "CSI1_LN3_N") (pinfunction "4") (pintype "passive"))
  )
	(footprint "sa800u-baseboard-hw-footprints:C_0402_1005Metric" (layer "B.Cu")
    (tedit 616D63CF)
    (at 131.2 103.3)
    (descr "Capacitor SMD 0402")
    (tags "capacitor SMD 0402")
    (property "Author" "Antmicro")
    (property "Dielectric" "C0G")
    (property "License" "Apache-2.0")
    (property "MPN" "GCM1555C1H100GA16D")
    (property "Manufacturer" "Murata")
    (property "Sheetfile" "other-interfaces.kicad_sch")
    (property "Sheetname" "Other Interfaces")
    (property "Val" "10p")
    (property "Voltage" "50V")
    (attr smd)
    (fp_text reference "C118" (at 1.29 -0.55 180) (layer "B.SilkS")
      (effects (font (size 0.7 0.7) (thickness 0.15)) (justify left bottom mirror))
    )
    (fp_text value "C_10p_0402" (at 0 -1.4 180) (layer "B.Fab")
      (effects (font (size 0.7 0.7) (thickness 0.15)) (justify left bottom mirror))
    )
    (fp_text user "Author: Antmicro" (at -0.932 -4.17 180) (layer "B.Fab") hide
      (effects (font (size 0.7 0.7) (thickness 0.15)) (justify left bottom mirror))
    )
    (fp_text user "License: Apache-2.0" (at -0.932 -5.17 180) (layer "B.Fab") hide
      (effects (font (size 0.7 0.7) (thickness 0.15)) (justify left bottom mirror))
    )
    (fp_text user "${REFERENCE}" (at -0.932 -3.168 180) (layer "B.Fab") hide
      (effects (font (size 0.7 0.7) (thickness 0.15)) (justify left bottom mirror))
    )
    (fp_rect (start -0.94 0.47) (end 0.94 -0.47) (layer "B.CrtYd") (width 0.05) (fill none))
    (fp_rect (start -0.499 0.249) (end 0.499 -0.249) (layer "B.Fab") (width 0.15) (fill none))
    (pad "1" smd roundrect (at -0.484 0) (size 0.59 0.64) (layers "B.Cu" "B.Paste" "B.Mask") (roundrect_rratio 0.25)
      (net 227 "/Other Interfaces/SD_VDD_R") (pintype "passive"))
    (pad "2" smd roundrect (at 0.484 0) (size 0.59 0.64) (layers "B.Cu" "B.Paste" "B.Mask") (roundrect_rratio 0.25)
      (net 1 "GND") (pintype "passive"))
  )
	(footprint "sa800u-baseboard-hw-footprints:C_0603_1608Metric" (layer "B.Cu")
    (tedit 5D5E94D2)
    (at 131.5 104.5)
    (descr "Capacitor SMD 0603")
    (tags "capacitor 0603")
    (property "Author" "Antmicro")
    (property "Dielectric" "")
    (property "License" "Apache-2.0")
    (property "MPN" "C1608X5R1V225K080AC")
    (property "Manufacturer" "TDK")
    (property "Sheetfile" "other-interfaces.kicad_sch")
    (property "Sheetname" "Other Interfaces")
    (property "Val" "2u2")
    (property "Voltage" "")
    (attr smd)
    (fp_text reference "C119" (at -1.23 0.66 180) (layer "B.SilkS")
      (effects (font (size 0.7 0.7) (thickness 0.15)) (justify left bottom mirror))
    )
    (fp_text value "C_2u2_0603" (at 0 -1.6 180) (layer "B.Fab")
      (effects (font (size 0.7 0.7) (thickness 0.15)) (justify left bottom mirror))
    )
    (fp_text user "License: Apache-2.0" (at -1.682 -5.895 180) (layer "B.Fab") hide
      (effects (font (size 0.7 0.7) (thickness 0.15)) (justify left bottom mirror))
    )
    (fp_text user "${REFERENCE}" (at -1.682 -3.895 180) (layer "B.Fab") hide
      (effects (font (size 0.7 0.7) (thickness 0.15)) (justify left bottom mirror))
    )
    (fp_text user "Author: Antmicro" (at -1.682 -4.894 180) (layer "B.Fab") hide
      (effects (font (size 0.7 0.7) (thickness 0.15)) (justify left bottom mirror))
    )
    (fp_line (start -0.3 0.3) (end 0.3 0.3) (layer "B.SilkS") (width 0.15))
    (fp_line (start -0.3 -0.3) (end 0.3 -0.3) (layer "B.SilkS") (width 0.15))
    (fp_rect (start -1.24 0.7) (end 1.24 -0.7) (layer "B.CrtYd") (width 0.05) (fill none))
    (fp_rect (start -0.8 0.4) (end 0.8 -0.4) (layer "B.Fab") (width 0.15) (fill none))
    (pad "1" smd roundrect (at -0.7 0) (size 0.6 0.8) (layers "B.Cu" "B.Paste" "B.Mask") (roundrect_rratio 0.2)
      (net 227 "/Other Interfaces/SD_VDD_R") (pintype "passive"))
    (pad "2" smd roundrect (at 0.7 0) (size 0.6 0.8) (layers "B.Cu" "B.Paste" "B.Mask") (roundrect_rratio 0.2)
      (net 1 "GND") (pintype "passive"))
  )
)
